# SCM (Grand Teton) — schematic netlist excerpt (pin names and nets, part order shuffled) for the footprints in the layout excerpt that follows; sources: Cadence DE-HDL packaged netlist, KiCad conversion of 12092022_DA0F0TMDCD0_F0T_Management_Board_D_brd_V3_OCP.brd

C301  Q_CAP  0.1UF 25V 10% X7R  pkg 0402  page 55 : A = P3V3_LDO ; B = GND
R368  Q_RES  120 1% CHIP  pkg 0402LF  page 20 : A = M_BMC_DDR4_MCS_N ; B = P1V2_AUX

(kicad_pcb
	(version 20260206)
	(generator "pcbnew")
	(generator_version "10.0")
	(general
		(thickness 1.6)
		(legacy_teardrops no)
	)
	(paper "A4")
	(title_block
		(title "12092022_DA0F0TMDCD0_F0T_Management_Board_D_brd_V3_OCP.brd")
		(comment 1 "Grand Teton / footprints 1371-1373 of 1440")
	)
	(layers
		(0 "F.Cu" signal "TOP")
		(4 "In1.Cu" signal "GND")
		(6 "In2.Cu" signal "IN1")
		(8 "In3.Cu" signal "GND1")
		(10 "In4.Cu" signal "IN2")
		(12 "In5.Cu" signal "VCC")
		(14 "In6.Cu" signal "VCC1")
		(16 "In7.Cu" signal "IN3")
		(18 "In8.Cu" signal "GND2")
		(20 "In9.Cu" signal "IN4")
		(22 "In10.Cu" signal "GND3")
		(2 "B.Cu" signal "BOTTOM")
		(9 "F.Adhes" user "F.Adhesive")
		(11 "B.Adhes" user "B.Adhesive")
		(13 "F.Paste" user "Package Geometry/Pastemask Top")
		(15 "B.Paste" user "Package Geometry/Pastemask Bottom")
		(5 "F.SilkS" user "Ref Des/Silkscreen Top")
		(7 "B.SilkS" user "Ref Des/Silkscreen Bottom")
		(1 "F.Mask" user "Board Geometry/Soldermask Top")
		(3 "B.Mask" user "Board Geometry/Soldermask Bottom")
		(17 "Dwgs.User" user "User.Drawings")
		(19 "Cmts.User" user "User.Comments")
		(21 "Eco1.User" user "User.Eco1")
		(23 "Eco2.User" user "User.Eco2")
		(25 "Edge.Cuts" user "Board Geometry/Outline")
		(27 "Margin" user)
		(31 "F.CrtYd" user "Package Geometry/Place Bound Top")
		(29 "B.CrtYd" user "Package Geometry/Place Bound Bottom")
		(35 "F.Fab" user "Ref Des/Assembly Top")
		(33 "B.Fab" user "Ref Des/Assembly Bottom")
	)
	(footprint ""
		(layer "B.Cu")
		(at 85.29955 -39.347394 180)
		(property "Reference" "R368"
			(at 0 0 0)
			(layer "B.SilkS")
			(hide yes)
			(effects
				(font
					(size 1.27 1.27)
				)
				(justify mirror)
			)
		)
		(property "Value" ""
			(at 0 0 0)
			(layer "B.Fab")
			(effects
				(font
					(size 1.27 1.27)
				)
				(justify mirror)
			)
		)
		(duplicate_pad_numbers_are_jumpers no)
		(fp_line
			(start 0.7874 0.4064)
			(end 0.7874 -0.4064)
			(stroke
				(width 0.1524)
				(type default)
			)
			(layer "B.SilkS")
		)
		(fp_line
			(start 0.7874 -0.4064)
			(end -0.7874 -0.4064)
			(stroke
				(width 0.1524)
				(type default)
			)
			(layer "B.SilkS")
		)
		(fp_line
			(start -0.7874 0.4064)
			(end 0.7874 0.4064)
			(stroke
				(width 0.1524)
				(type default)
			)
			(layer "B.SilkS")
		)
		(fp_line
			(start -0.7874 -0.4064)
			(end -0.7874 0.4064)
			(stroke
				(width 0.1524)
				(type default)
			)
			(layer "B.SilkS")
		)
		(fp_line
			(start 0.67945 0.3048)
			(end 0.67945 -0.305054)
			(stroke
				(width 0.1)
				(type default)
			)
			(layer "B.Fab")
		)
		(fp_line
			(start 0.67945 -0.305054)
			(end 0.12065 -0.305054)
			(stroke
				(width 0.1)
				(type default)
			)
			(layer "B.Fab")
		)
		(fp_line
			(start 0.12065 0.3048)
			(end 0.67945 0.3048)
			(stroke
				(width 0.1)
				(type default)
			)
			(layer "B.Fab")
		)
		(fp_line
			(start 0.12065 0.2794)
			(end 0.12065 0.3048)
			(stroke
				(width 0.1)
				(type default)
			)
			(layer "B.Fab")
		)
		(fp_line
			(start 0.12065 -0.2794)
			(end -0.12065 -0.2794)
			(stroke
				(width 0.1)
				(type default)
			)
			(layer "B.Fab")
		)
		(fp_line
			(start 0.12065 -0.305054)
			(end 0.12065 -0.2794)
			(stroke
				(width 0.1)
				(type default)
			)
			(layer "B.Fab")
		)
		(fp_line
			(start -0.120396 0.3048)
			(end -0.120396 0.2794)
			(stroke
				(width 0.1)
				(type default)
			)
			(layer "B.Fab")
		)
		(fp_line
			(start -0.120396 0.2794)
			(end 0.12065 0.2794)
			(stroke
				(width 0.1)
				(type default)
			)
			(layer "B.Fab")
		)
		(fp_line
			(start -0.12065 -0.2794)
			(end -0.12065 -0.3048)
			(stroke
				(width 0.1)
				(type default)
			)
			(layer "B.Fab")
		)
		(fp_line
			(start -0.12065 -0.3048)
			(end -0.67945 -0.3048)
			(stroke
				(width 0.1)
				(type default)
			)
			(layer "B.Fab")
		)
		(fp_line
			(start -0.67945 0.3048)
			(end -0.120396 0.3048)
			(stroke
				(width 0.1)
				(type default)
			)
			(layer "B.Fab")
		)
		(fp_line
			(start -0.67945 -0.3048)
			(end -0.67945 0.3048)
			(stroke
				(width 0.1)
				(type default)
			)
			(layer "B.Fab")
		)
		(pad "1" smd circle
			(at 0.40005 0)
			(size 0 0)
			(layers "B.Cu" "B.Mask" "B.Paste")
			(net "M_BMC_DDR4_MCS_N")
		)
		(pad "2" smd circle
			(at -0.40005 0)
			(size 0 0)
			(layers "B.Cu" "B.Mask" "B.Paste")
			(net "P1V2_AUX")
		)
	)
	(footprint ""
		(layer "B.Cu")
		(at 75.438 -68.707)
		(property "Reference" ""
			(at 0 0 0)
			(layer "B.SilkS")
			(hide yes)
			(effects
				(font
					(size 1.27 1.27)
				)
				(justify mirror)
			)
		)
		(property "Value" ""
			(at 0 0 0)
			(layer "B.Fab")
			(effects
				(font
					(size 1.27 1.27)
				)
				(justify mirror)
			)
		)
		(duplicate_pad_numbers_are_jumpers no)
		(pad "1" smd circle
			(at 0 0 180)
			(size 0.9906 0.9906)
			(layers "B.Cu" "B.Mask" "B.Paste")
			(net "Net_599")
		)
		(zone
			(layer "B.Cu")
			(hatch none 0.5)
			(connect_pads
				(clearance 0)
			)
			(min_thickness 0.25)
			(keepout
				(tracks not_allowed)
				(vias allowed)
				(pads allowed)
				(copperpour not_allowed)
				(footprints allowed)
			)
			(placement
				(enabled no)
				(sheetname "")
			)
			(fill
				(thermal_gap 0.5)
				(thermal_bridge_width 0.5)
				(island_removal_mode 0)
			)
			(polygon
				(pts
					(arc
						(start 77.0636 -68.707)
						(mid 73.8124 -68.707)
						(end 77.0636 -68.707)
					)
				)
			)
		)
	)
	(footprint ""
		(layer "B.Cu")
		(at 79.4512 -66.1162 180)
		(property "Reference" "C301"
			(at 0 0 0)
			(layer "B.SilkS")
			(hide yes)
			(effects
				(font
					(size 1.27 1.27)
				)
				(justify mirror)
			)
		)
		(property "Value" ""
			(at 0 0 0)
			(layer "B.Fab")
			(effects
				(font
					(size 1.27 1.27)
				)
				(justify mirror)
			)
		)
		(duplicate_pad_numbers_are_jumpers no)
		(fp_line
			(start 0.7874 0.4064)
			(end 0.7874 -0.4064)
			(stroke
				(width 0.1524)
				(type default)
			)
			(layer "B.SilkS")
		)
		(fp_line
			(start 0.7874 -0.4064)
			(end -0.7874 -0.4064)
			(stroke
				(width 0.1524)
				(type default)
			)
			(layer "B.SilkS")
		)
		(fp_line
			(start -0.7874 0.4064)
			(end 0.7874 0.4064)
			(stroke
				(width 0.1524)
				(type default)
			)
			(layer "B.SilkS")
		)
		(fp_line
			(start -0.7874 -0.4064)
			(end -0.7874 0.4064)
			(stroke
				(width 0.1524)
				(type default)
			)
			(layer "B.SilkS")
		)
		(fp_line
			(start 0.67945 0.3048)
			(end 0.67945 -0.305054)
			(stroke
				(width 0.1)
				(type default)
			)
			(layer "B.Fab")
		)
		(fp_line
			(start 0.67945 -0.305054)
			(end 0.12065 -0.305054)
			(stroke
				(width 0.1)
				(type default)
			)
			(layer "B.Fab")
		)
		(fp_line
			(start 0.12065 0.3048)
			(end 0.67945 0.3048)
			(stroke
				(width 0.1)
				(type default)
			)
			(layer "B.Fab")
		)
		(fp_line
			(start 0.12065 0.2794)
			(end 0.12065 0.3048)
			(stroke
				(width 0.1)
				(type default)
			)
			(layer "B.Fab")
		)
		(fp_line
			(start 0.12065 -0.2794)
			(end -0.12065 -0.2794)
			(stroke
				(width 0.1)
				(type default)
			)
			(layer "B.Fab")
		)
		(fp_line
			(start 0.12065 -0.305054)
			(end 0.12065 -0.2794)
			(stroke
				(width 0.1)
				(type default)
			)
			(layer "B.Fab")
		)
		(fp_line
			(start -0.120396 0.3048)
			(end -0.120396 0.2794)
			(stroke
				(width 0.1)
				(type default)
			)
			(layer "B.Fab")
		)
		(fp_line
			(start -0.120396 0.2794)
			(end 0.12065 0.2794)
			(stroke
				(width 0.1)
				(type default)
			)
			(layer "B.Fab")
		)
		(fp_line
			(start -0.12065 -0.2794)
			(end -0.12065 -0.3048)
			(stroke
				(width 0.1)
				(type default)
			)
			(layer "B.Fab")
		)
		(fp_line
			(start -0.12065 -0.3048)
			(end -0.67945 -0.3048)
			(stroke
				(width 0.1)
				(type default)
			)
			(layer "B.Fab")
		)
		(fp_line
			(start -0.67945 0.3048)
			(end -0.120396 0.3048)
			(stroke
				(width 0.1)
				(type default)
			)
			(layer "B.Fab")
		)
		(fp_line
			(start -0.67945 -0.3048)
			(end -0.67945 0.3048)
			(stroke
				(width 0.1)
				(type default)
			)
			(layer "B.Fab")
		)
		(pad "1" smd circle
			(at 0.40005 0)
			(size 0 0)
			(layers "B.Cu" "B.Mask" "B.Paste")
			(net "P3V3_LDO")
		)
		(pad "2" smd circle
			(at -0.40005 0)
			(size 0 0)
			(layers "B.Cu" "B.Mask" "B.Paste")
			(net "GND")
		)
	)
)
